#ISCELL
  pure_quanta quanta_title_block_c *
  *
#CELL
  pure_quanta q_cap *
  page67_i100
#CELL
  pure_quanta q_cap *
  page67_i101
#CELL
  pure_quanta q_cap *
  page67_i102
#CELL
  pure_quanta q_cap *
  page67_i103
#CELL
  pure_quanta q_cap *
  page67_i104
#ISCELL
  pure_quanta_power universal_gnd *
  page67_i105
#CELL
  pure_quanta q_cap *
  page67_i106
#ISCELL
  pure_quanta_power universal_gnd *
  page67_i107
#CELL
  pure_quanta q_cap *
  page67_i108
#CELL
  pure_quanta q_cap *
  page67_i109
#CELL
  pure_quanta q_cap *
  page67_i110
#ISCELL
  pure_quanta_power universal_power *
  page67_i111
#CELL
  pure_quanta q_cap *
  page67_i112
#CELL
  pure_quanta q_cap *
  page67_i113
#ISCELL
  pure_quanta_power universal_power *
  page67_i114
#CELL
  pure_quanta q_cap *
  page67_i115
#CELL
  pure_quanta q_cap *
  page67_i116
#CELL
  pure_quanta q_cap *
  page67_i117
#CELL
  pure_quanta q_cap *
  page67_i118
#ISCELL
  pure_quanta_power universal_gnd *
  page67_i119
#CELL
  pure_quanta q_cap *
  page67_i120
#CELL
  pure_quanta q_cap *
  page67_i121
#CELL
  pure_quanta q_cap *
  page67_i122
#CELL
  pure_quanta q_cap *
  page67_i123
#CELL
  pure_quanta q_cap *
  page67_i124
#CELL
  pure_quanta q_cap *
  page67_i125
#ISCELL
  pure_quanta_power universal_gnd *
  page67_i126
#CELL
  pure_quanta q_cap *
  page67_i127
#CELL
  pure_quanta q_cap *
  page67_i128
#CELL
  pure_quanta q_cap *
  page67_i129
#ISCELL
  pure_quanta_power universal_gnd *
  page67_i130
#CELL
  pure_quanta q_cap *
  page67_i131
#ISCELL
  pure_quanta_power universal_power *
  page67_i132
#CELL
  pure_quanta q_cap *
  page67_i133
#CELL
  pure_quanta q_cap *
  page67_i134
#CELL
  pure_quanta q_cap *
  page67_i135
#CELL
  pure_quanta q_cap *
  page67_i136
#CELL
  pure_quanta q_cap *
  page67_i137
#CELL
  pure_quanta q_cap *
  page67_i138
#CELL
  pure_quanta q_cap *
  page67_i139
#ISCELL
  pure_quanta_power universal_power *
  page67_i140
#CELL
  pure_quanta q_cap *
  page67_i141
#ISCELL
  pure_quanta_power universal_gnd *
  page67_i142
#CELL
  pure_quanta q_cap *
  page67_i143
#ISCELL
  pure_quanta_power universal_gnd *
  page67_i82
#CELL
  pure_quanta q_cap *
  page67_i83
#ISCELL
  pure_quanta_power universal_power *
  page67_i84
#CELL
  pure_quanta q_cap *
  page67_i85
#CELL
  pure_quanta q_cap *
  page67_i86
#CELL
  pure_quanta q_cap *
  page67_i87
#ISCELL
  pure_quanta_power universal_power *
  page67_i88
#CELL
  pure_quanta q_cap *
  page67_i89
#CELL
  pure_quanta q_cap *
  page67_i90
#ISCELL
  pure_quanta_power universal_power *
  page67_i91
#CELL
  pure_quanta q_cap *
  page67_i92
#CELL
  pure_quanta q_cap *
  page67_i93
#CELL
  pure_quanta q_cap *
  page67_i94
#CELL
  pure_quanta q_cap *
  page67_i95
#CELL
  pure_quanta q_cap *
  page67_i96
#CELL
  pure_quanta q_cap *
  page67_i97
#CELL
  pure_quanta q_cap *
  page67_i98
#CELL
  pure_quanta q_cap *
  page67_i99
